(kicad_pcb
	(version 20241229)
	(generator "pcbnew")
	(generator_version "9.0")
	(general
		(thickness 1.552)
		(legacy_teardrops no)
	)
	(paper "A4")
	(title_block
		(date "2023-07-25")
		(rev "1.1.4")
		(comment 9 "footprints 164-167 of 379")
	)
	(layers
		(0 "F.Cu" signal)
		(4 "In1.Cu" signal)
		(6 "In2.Cu" signal)
		(8 "In3.Cu" signal)
		(10 "In4.Cu" signal)
		(12 "In5.Cu" signal)
		(14 "In6.Cu" signal)
		(2 "B.Cu" signal)
		(9 "F.Adhes" user "F.Adhesive")
		(11 "B.Adhes" user "B.Adhesive")
		(13 "F.Paste" user)
		(15 "B.Paste" user)
		(5 "F.SilkS" user "F.Silkscreen")
		(7 "B.SilkS" user "B.Silkscreen")
		(1 "F.Mask" user)
		(3 "B.Mask" user)
		(17 "Dwgs.User" user "User.Drawings")
		(19 "Cmts.User" user "User.Comments")
		(21 "Eco1.User" user "User.Eco1")
		(23 "Eco2.User" user "User.Eco2")
		(25 "Edge.Cuts" user)
		(27 "Margin" user)
		(31 "F.CrtYd" user "F.Courtyard")
		(29 "B.CrtYd" user "B.Courtyard")
		(35 "F.Fab" user)
		(33 "B.Fab" user)
	)
	(footprint "antmicro-footprints:Conn_JST_SH_1x6_SM06B-SRSS-TB-LF-SN"
		(layer "F.Cu")
		(at 151.5 121.97)
		(property "Reference" "J9"
			(at 0 -3.15 0)
			(layer "F.SilkS")
			(effects
				(font
					(size 0.7 0.7)
					(thickness 0.15)
				)
				(justify left bottom)
			)
		)
		(property "Value" "JST_GH_1x6_SM06B-SRSS-TB-LF-SN"
			(at 0 3.7 0)
			(layer "F.Fab")
			(effects
				(font
					(size 0.7 0.7)
					(thickness 0.15)
				)
				(justify left bottom)
			)
		)
		(property "Datasheet" "https://www.jst-mfg.com/product/pdf/eng/eSH.pdf"
			(at 0 0 0)
			(layer "F.Fab")
			(hide yes)
			(effects
				(font
					(size 1.27 1.27)
					(thickness 0.15)
				)
			)
		)
		(property "Description" "Pin Header, Right Angle, Wire-to-Board, 1 mm, 1 Rows, 6 Contacts, Surface Mount Right Angle, SR"
			(at 0 0 0)
			(layer "F.Fab")
			(hide yes)
			(effects
				(font
					(size 1.27 1.27)
					(thickness 0.15)
				)
			)
		)
		(property "Author" "Antmicro"
			(at 0 0 0)
			(layer "F.Fab")
			(hide yes)
			(effects
				(font
					(size 1 1)
					(thickness 0.15)
				)
			)
		)
		(property "License" "Apache-2.0"
			(at 0 0 0)
			(layer "F.Fab")
			(hide yes)
			(effects
				(font
					(size 1 1)
					(thickness 0.15)
				)
			)
		)
		(property "MPN" "SM06B-SRSS-TB(LF)(SN)"
			(at 0 0 0)
			(layer "F.Fab")
			(hide yes)
			(effects
				(font
					(size 1 1)
					(thickness 0.15)
				)
			)
		)
		(property "Manufacturer" "JST Automotive Connectors"
			(at 0 0 0)
			(layer "F.Fab")
			(hide yes)
			(effects
				(font
					(size 1 1)
					(thickness 0.15)
				)
			)
		)
		(sheetname "/Peripherals/")
		(sheetfile "peripherals.kicad_sch")
		(attr smd)
		(fp_line
			(start -4.2 -1.9)
			(end -4.2 0.7)
			(stroke
				(width 0.15)
				(type solid)
			)
			(layer "F.SilkS")
		)
		(fp_line
			(start -3.1 -1.9)
			(end -4.2 -1.9)
			(stroke
				(width 0.15)
				(type solid)
			)
			(layer "F.SilkS")
		)
		(fp_line
			(start -2.9 2.6)
			(end 2.9 2.6)
			(stroke
				(width 0.15)
				(type solid)
			)
			(layer "F.SilkS")
		)
		(fp_line
			(start 3.1 -1.9)
			(end 4.2 -1.9)
			(stroke
				(width 0.15)
				(type solid)
			)
			(layer "F.SilkS")
		)
		(fp_line
			(start 4.2 -1.9)
			(end 4.2 0.7)
			(stroke
				(width 0.15)
				(type solid)
			)
			(layer "F.SilkS")
		)
		(fp_circle
			(center -3.2 -2.4)
			(end -3.15 -2.4)
			(stroke
				(width 0.15)
				(type solid)
			)
			(fill yes)
			(layer "F.SilkS")
		)
		(fp_rect
			(start -4.65 -3.12)
			(end 4.65 2.92)
			(stroke
				(width 0.05)
				(type solid)
			)
			(fill no)
			(layer "F.CrtYd")
		)
		(fp_rect
			(start -4 -2.475)
			(end 4 2.475)
			(stroke
				(width 0.15)
				(type solid)
			)
			(fill no)
			(layer "F.Fab")
		)
		(fp_text user "Author: Antmicro"
			(at -4.65 4.92 0)
			(layer "F.Fab")
			(effects
				(font
					(size 0.7 0.7)
					(thickness 0.15)
				)
				(justify left bottom)
			)
		)
		(fp_text user "License: Apache-2.0"
			(at -4.65 7.32 0)
			(layer "F.Fab")
			(effects
				(font
					(size 0.7 0.7)
					(thickness 0.15)
				)
				(justify left bottom)
			)
		)
		(fp_text user "${REFERENCE}"
			(at -4.65 6.12 0)
			(layer "F.Fab")
			(effects
				(font
					(size 0.7 0.7)
					(thickness 0.15)
				)
				(justify left bottom)
			)
		)
		(pad "1" smd roundrect
			(at -2.5 -2.1 180)
			(size 0.6 1.55)
			(layers "F.Cu" "F.Mask" "F.Paste")
			(roundrect_rratio 0.25)
			(net 331 "/Peripherals/3V3_MISC")
			(pintype "passive")
		)
		(pad "2" smd roundrect
			(at -1.5 -2.1 180)
			(size 0.6 1.55)
			(layers "F.Cu" "F.Mask" "F.Paste")
			(roundrect_rratio 0.25)
			(net 332 "GPIO0")
			(pintype "passive")
		)
		(pad "3" smd roundrect
			(at -0.5 -2.1 180)
			(size 0.6 1.55)
			(layers "F.Cu" "F.Mask" "F.Paste")
			(roundrect_rratio 0.25)
			(net 333 "GPIO1")
			(pintype "passive")
		)
		(pad "4" smd roundrect
			(at 0.5 -2.1 180)
			(size 0.6 1.55)
			(layers "F.Cu" "F.Mask" "F.Paste")
			(roundrect_rratio 0.25)
			(net 334 "GPIO2")
			(pintype "passive")
		)
		(pad "5" smd roundrect
			(at 1.5 -2.1 180)
			(size 0.6 1.55)
			(layers "F.Cu" "F.Mask" "F.Paste")
			(roundrect_rratio 0.25)
			(net 335 "GPIO3")
			(pintype "passive")
		)
		(pad "6" smd roundrect
			(at 2.5 -2.1 180)
			(size 0.6 1.55)
			(layers "F.Cu" "F.Mask" "F.Paste")
			(roundrect_rratio 0.25)
			(net 1 "GND")
			(pintype "passive")
		)
		(pad "MP" smd roundrect
			(at -3.8 1.775)
			(size 1.2 1.8)
			(layers "F.Cu" "F.Mask" "F.Paste")
			(roundrect_rratio 0.25)
			(net 1 "GND")
			(pintype "passive")
		)
		(pad "MP" smd roundrect
			(at 3.8 1.775)
			(size 1.2 1.8)
			(layers "F.Cu" "F.Mask" "F.Paste")
			(roundrect_rratio 0.25)
			(net 1 "GND")
			(pintype "passive")
		)
	)
	(footprint "antmicro-footprints:R_0402_1005Metric"
		(layer "F.Cu")
		(at 167.2 95.6)
		(descr "Resistor SMD 0402")
		(tags "resistor SMD 0402")
		(property "Reference" "R74"
			(at -3.67 0.34 0)
			(layer "F.SilkS")
			(effects
				(font
					(size 0.65 0.65)
					(thickness 0.15)
				)
				(justify left bottom)
			)
		)
		(property "Value" "R_0R_0402"
			(at 0 1.4 0)
			(layer "F.Fab")
			(hide yes)
			(effects
				(font
					(size 0.7 0.7)
					(thickness 0.15)
				)
				(justify left bottom)
			)
		)
		(property "Datasheet" "https://industrial.panasonic.com/cdbs/www-data/pdf/RDA0000/AOA0000C301.pdf"
			(at 0 0 0)
			(layer "F.Fab")
			(hide yes)
			(effects
				(font
					(size 1.27 1.27)
					(thickness 0.15)
				)
			)
		)
		(property "Description" "SMD Chip Resistor, Jumper, 0 ohm, 100 mW, 0402 [1005 Metric], Thick Film, General Purpose"
			(at 0 0 0)
			(layer "F.Fab")
			(hide yes)
			(effects
				(font
					(size 1.27 1.27)
					(thickness 0.15)
				)
			)
		)
		(property "Author" "Antmicro"
			(at 0 0 0)
			(layer "F.Fab")
			(hide yes)
			(effects
				(font
					(size 1 1)
					(thickness 0.15)
				)
			)
		)
		(property "Current" "1A"
			(at 0 0 0)
			(layer "F.Fab")
			(hide yes)
			(effects
				(font
					(size 1 1)
					(thickness 0.15)
				)
			)
		)
		(property "License" "Apache-2.0"
			(at 0 0 0)
			(layer "F.Fab")
			(hide yes)
			(effects
				(font
					(size 1 1)
					(thickness 0.15)
				)
			)
		)
		(property "MPN" "ERJ2GE0R00X"
			(at 0 0 0)
			(layer "F.Fab")
			(hide yes)
			(effects
				(font
					(size 1 1)
					(thickness 0.15)
				)
			)
		)
		(property "Manufacturer" "Panasonic"
			(at 0 0 0)
			(layer "F.Fab")
			(hide yes)
			(effects
				(font
					(size 1 1)
					(thickness 0.15)
				)
			)
		)
		(property "Tolerance" "~"
			(at 0 0 0)
			(layer "F.Fab")
			(hide yes)
			(effects
				(font
					(size 1 1)
					(thickness 0.15)
				)
			)
		)
		(property "Val" "0R"
			(at 0 0 0)
			(layer "F.Fab")
			(hide yes)
			(effects
				(font
					(size 1 1)
					(thickness 0.15)
				)
			)
		)
		(sheetname "/Peripherals/")
		(sheetfile "peripherals.kicad_sch")
		(attr smd)
		(fp_rect
			(start -0.925 -0.47)
			(end 0.925 0.47)
			(stroke
				(width 0.05)
				(type default)
			)
			(fill no)
			(layer "F.CrtYd")
		)
		(fp_rect
			(start -0.5 -0.25)
			(end 0.5 0.25)
			(stroke
				(width 0.15)
				(type solid)
			)
			(fill no)
			(layer "F.Fab")
		)
		(fp_text user "${REFERENCE}"
			(at -0.95 3.168 0)
			(layer "F.Fab")
			(effects
				(font
					(size 0.7 0.7)
					(thickness 0.15)
				)
				(justify left bottom)
			)
		)
		(fp_text user "License: Apache-2.0"
			(at -0.95 5.169 0)
			(layer "F.Fab")
			(effects
				(font
					(size 0.7 0.7)
					(thickness 0.15)
				)
				(justify left bottom)
			)
		)
		(fp_text user "Author: Antmicro"
			(at -0.95 4.169 0)
			(layer "F.Fab")
			(effects
				(font
					(size 0.7 0.7)
					(thickness 0.15)
				)
				(justify left bottom)
			)
		)
		(pad "1" smd roundrect
			(at -0.48 0)
			(size 0.59 0.64)
			(layers "F.Cu" "F.Mask" "F.Paste")
			(roundrect_rratio 0.25)
			(net 89 "/Peripherals/FFC1_RESET")
			(pintype "passive")
		)
		(pad "2" smd roundrect
			(at 0.48 0)
			(size 0.59 0.64)
			(layers "F.Cu" "F.Mask" "F.Paste")
			(roundrect_rratio 0.25)
			(net 336 "Net-(J4-Pad33)")
			(pintype "passive")
		)
	)
	(footprint "antmicro-footprints:SOT-23-5"
		(layer "F.Cu")
		(at 143.14 115.45 180)
		(property "Reference" "U9"
			(at -1.49 -2.89 0)
			(layer "F.SilkS")
			(effects
				(font
					(size 0.65 0.65)
					(thickness 0.15)
				)
				(justify right bottom)
			)
		)
		(property "Value" "AP7330-W5-7"
			(at 0.002 2.799 0)
			(layer "F.Fab")
			(hide yes)
			(effects
				(font
					(size 0.7 0.7)
					(thickness 0.15)
				)
				(justify right bottom)
			)
		)
		(property "Datasheet" "https://www.diodes.com/assets/Datasheets/AP7330.pdf"
			(at 0 0 180)
			(layer "F.Fab")
			(hide yes)
			(effects
				(font
					(size 1.27 1.27)
					(thickness 0.15)
				)
			)
		)
		(property "Description" "Voltage regulator"
			(at 0 0 180)
			(layer "F.Fab")
			(hide yes)
			(effects
				(font
					(size 1.27 1.27)
					(thickness 0.15)
				)
			)
		)
		(property "Author" "Antmicro"
			(at 286.28 230.9 0)
			(layer "F.Fab")
			(hide yes)
			(effects
				(font
					(size 1 1)
					(thickness 0.15)
				)
			)
		)
		(property "License" "Apache-2.0"
			(at 286.28 230.9 0)
			(layer "F.Fab")
			(hide yes)
			(effects
				(font
					(size 1 1)
					(thickness 0.15)
				)
			)
		)
		(property "MPN" "AP7330-W5-7"
			(at 286.28 230.9 0)
			(layer "F.Fab")
			(hide yes)
			(effects
				(font
					(size 1 1)
					(thickness 0.15)
				)
			)
		)
		(property "Manufacturer" "Diodes Incorporated"
			(at 286.28 230.9 0)
			(layer "F.Fab")
			(hide yes)
			(effects
				(font
					(size 1 1)
					(thickness 0.15)
				)
			)
		)
		(sheetname "/Power Supply/")
		(sheetfile "supply.kicad_sch")
		(attr smd)
		(fp_line
			(start 0.8 1.599)
			(end 0.549 1.599)
			(stroke
				(width 0.15)
				(type solid)
			)
			(layer "F.SilkS")
		)
		(fp_line
			(start 0.8 1.3)
			(end 0.8 1.599)
			(stroke
				(width 0.15)
				(type solid)
			)
			(layer "F.SilkS")
		)
		(fp_line
			(start 0.8 0.55)
			(end 0.8 -0.55)
			(stroke
				(width 0.15)
				(type solid)
			)
			(layer "F.SilkS")
		)
		(fp_line
			(start 0.8 -1.3)
			(end 0.8 -1.6)
			(stroke
				(width 0.15)
				(type solid)
			)
			(layer "F.SilkS")
		)
		(fp_line
			(start 0.8 -1.6)
			(end 0.5 -1.6)
			(stroke
				(width 0.15)
				(type solid)
			)
			(layer "F.SilkS")
		)
		(fp_line
			(start -0.55 1.6)
			(end -0.85 1.6)
			(stroke
				(width 0.15)
				(type solid)
			)
			(layer "F.SilkS")
		)
		(fp_line
			(start -0.8 -1.6)
			(end -0.5 -1.6)
			(stroke
				(width 0.15)
				(type solid)
			)
			(layer "F.SilkS")
		)
		(fp_line
			(start -0.8 -1.6)
			(end -0.8 -1.3)
			(stroke
				(width 0.15)
				(type solid)
			)
			(layer "F.SilkS")
		)
		(fp_line
			(start -0.85 1.6)
			(end -0.85 1.301)
			(stroke
				(width 0.15)
				(type solid)
			)
			(layer "F.SilkS")
		)
		(fp_circle
			(center -1.25 -1.5)
			(end -1.2 -1.5)
			(stroke
				(width 0.15)
				(type solid)
			)
			(fill yes)
			(layer "F.SilkS")
		)
		(fp_rect
			(start 1.9 -1.76)
			(end -1.9 1.75)
			(stroke
				(width 0.05)
				(type solid)
			)
			(fill no)
			(layer "F.CrtYd")
		)
		(fp_line
			(start -0.398 -1.526)
			(end -0.874 -1.05)
			(stroke
				(width 0.15)
				(type solid)
			)
			(layer "F.Fab")
		)
		(fp_rect
			(start 0.874 1.523)
			(end -0.873 -1.525)
			(stroke
				(width 0.15)
				(type solid)
			)
			(fill no)
			(layer "F.Fab")
		)
		(pad "1" smd rect
			(at -1.351 -0.951 90)
			(size 0.55 1)
			(layers "F.Cu" "F.Mask" "F.Paste")
			(net 265 "Net-(U9-V_{IN})")
			(pinfunction "V_{IN}")
			(pintype "power_in")
		)
		(pad "2" smd rect
			(at -1.351 0 90)
			(size 0.55 1)
			(layers "F.Cu" "F.Mask" "F.Paste")
			(net 1 "GND")
			(pinfunction "GND")
			(pintype "power_in")
		)
		(pad "3" smd rect
			(at -1.351 0.949 90)
			(size 0.55 1)
			(layers "F.Cu" "F.Mask" "F.Paste")
			(net 269 "Net-(U9-EN)")
			(pinfunction "EN")
			(pintype "input")
		)
		(pad "4" smd rect
			(at 1.35 0.949 90)
			(size 0.55 1)
			(layers "F.Cu" "F.Mask" "F.Paste")
			(net 282 "Net-(U9-ADJ)")
			(pinfunction "ADJ")
			(pintype "passive")
		)
		(pad "5" smd rect
			(at 1.35 -0.951 90)
			(size 0.55 1)
			(layers "F.Cu" "F.Mask" "F.Paste")
			(net 279 "Net-(U9-V_{OUT})")
			(pinfunction "V_{OUT}")
			(pintype "power_out")
		)
	)
	(footprint "antmicro-footprints:R_0603_1608Metric"
		(layer "F.Cu")
		(at 158.29 79.7)
		(descr "Resistor SMD 0603")
		(tags "resistor SMD 0603")
		(property "Reference" "R113"
			(at -4.06 0.54 0)
			(layer "F.SilkS")
			(effects
				(font
					(size 0.65 0.65)
					(thickness 0.15)
				)
				(justify left bottom)
			)
		)
		(property "Value" "R_10k_0603"
			(at 0 1.6 0)
			(layer "F.Fab")
			(hide yes)
			(effects
				(font
					(size 0.7 0.7)
					(thickness 0.15)
				)
				(justify left bottom)
			)
		)
		(property "Datasheet" "https://www.bourns.com/docs/product-datasheets/cr.pdf"
			(at 0 0 0)
			(layer "F.Fab")
			(hide yes)
			(effects
				(font
					(size 1.27 1.27)
					(thickness 0.15)
				)
			)
		)
		(property "Description" "SMD Chip Resistor, 10 kohm, ± 1%, 100 mW, 0603 [1608 Metric], Thick Film, General Purpose"
			(at 0 0 0)
			(layer "F.Fab")
			(hide yes)
			(effects
				(font
					(size 1.27 1.27)
					(thickness 0.15)
				)
			)
		)
		(property "Author" "Antmicro"
			(at 0 0 0)
			(layer "F.Fab")
			(hide yes)
			(effects
				(font
					(size 1 1)
					(thickness 0.15)
				)
			)
		)
		(property "License" "Apache-2.0"
			(at 0 0 0)
			(layer "F.Fab")
			(hide yes)
			(effects
				(font
					(size 1 1)
					(thickness 0.15)
				)
			)
		)
		(property "MPN" "CR0603-FX-1002ELF"
			(at 0 0 0)
			(layer "F.Fab")
			(hide yes)
			(effects
				(font
					(size 1 1)
					(thickness 0.15)
				)
			)
		)
		(property "Manufacturer" "Bourns"
			(at 0 0 0)
			(layer "F.Fab")
			(hide yes)
			(effects
				(font
					(size 1 1)
					(thickness 0.15)
				)
			)
		)
		(property "Tolerance" "1%"
			(at 0 0 0)
			(layer "F.Fab")
			(hide yes)
			(effects
				(font
					(size 1 1)
					(thickness 0.15)
				)
			)
		)
		(property "Val" "10k"
			(at 0 0 0)
			(layer "F.Fab")
			(hide yes)
			(effects
				(font
					(size 1 1)
					(thickness 0.15)
				)
			)
		)
		(sheetname "/Peripherals/")
		(sheetfile "peripherals.kicad_sch")
		(attr smd)
		(fp_line
			(start -0.15 -0.4)
			(end 0.15 -0.4)
			(stroke
				(width 0.15)
				(type solid)
			)
			(layer "F.SilkS")
		)
		(fp_line
			(start -0.15 0.4)
			(end 0.15 0.4)
			(stroke
				(width 0.15)
				(type solid)
			)
			(layer "F.SilkS")
		)
		(fp_rect
			(start -1.25 -0.65)
			(end 1.25 0.65)
			(stroke
				(width 0.05)
				(type solid)
			)
			(fill no)
			(layer "F.CrtYd")
		)
		(fp_rect
			(start -0.8 -0.4)
			(end 0.8 0.4)
			(stroke
				(width 0.15)
				(type solid)
			)
			(fill no)
			(layer "F.Fab")
		)
		(fp_text user "Author: Antmicro"
			(at -1.25 4.9 0)
			(layer "F.Fab")
			(effects
				(font
					(size 0.7 0.7)
					(thickness 0.15)
				)
				(justify left bottom)
			)
		)
		(fp_text user "License: Apache-2.0"
			(at -1.25 5.9 0)
			(layer "F.Fab")
			(effects
				(font
					(size 0.7 0.7)
					(thickness 0.15)
				)
				(justify left bottom)
			)
		)
		(fp_text user "${REFERENCE}"
			(at -1.25 3.898 0)
			(layer "F.Fab")
			(effects
				(font
					(size 0.7 0.7)
					(thickness 0.15)
				)
				(justify left bottom)
			)
		)
		(pad "1" smd roundrect
			(at -0.7 0)
			(size 0.8 1)
			(layers "F.Cu" "F.Mask" "F.Paste")
			(roundrect_rratio 0.2)
			(net 2 "+3V3")
			(pintype "passive")
		)
		(pad "2" smd roundrect
			(at 0.7 0)
			(size 0.8 1)
			(layers "F.Cu" "F.Mask" "F.Paste")
			(roundrect_rratio 0.2)
			(net 314 "/Peripherals/QW_FLT")
			(pintype "passive")
		)
	)
)
